# TIMECARD (Time Appliance Project (Time Card)) — schematic netlist excerpt (pin names and nets, part order shuffled) for the footprints in the layout excerpt that follows; sources: Cadence DE-HDL packaged netlist, KiCad conversion of R4006-B0001-02_R01.brd

U6  TPS54824RNVR_VQFN18  TPS54424RNVT  pkg QFN18_138_P0197_V1  page 28
  BOOT  = XP3R3V_BT
  VIN_1  = VIN_XP3R3
  PGND_1  = SG
  PGND_2  = SG
  PGND_3  = SG
  SW_1  = XP3R3V_SW
  SW_2  = XP3R3V_SW
  PGND_4  = SG
  PGND_5  = SG
  PGND_6  = SG
  VIN_2  = VIN_XP3R3
  AGND  = XP3R3V_AGND
  \rt/clk\  = XP3R3V_RT
  FB  = XP3R3V_FB_R_TO_AGND
  COMP  = XP3R3V_COMP
  \ss/trk\  = XP3R3V_SS
  EN  = XP3R3V_EN
  PGOOD  = R_XP3R3V_PG

(kicad_pcb
	(version 20260206)
	(generator "pcbnew")
	(generator_version "10.0")
	(general
		(thickness 1.6)
		(legacy_teardrops no)
	)
	(paper "A4")
	(title_block
		(title "timecard-production-celestica-r4006 — R4006-B0001-02_R01.brd")
		(comment 1 "Time Appliance Project (Time Card) / footprints 548-548 of 1113")
	)
	(layers
		(0 "F.Cu" signal "TOP")
		(4 "In1.Cu" signal "L02_GND1")
		(6 "In2.Cu" signal "L03_SIG1")
		(8 "In3.Cu" signal "L04_GND2")
		(10 "In4.Cu" signal "L05_VCC1")
		(12 "In5.Cu" signal "L06_VCC2")
		(14 "In6.Cu" signal "L07_GND3")
		(16 "In7.Cu" signal "L08_SIG2")
		(18 "In8.Cu" signal "L09_GND4")
		(2 "B.Cu" signal "BOTTOM")
		(9 "F.Adhes" user "F.Adhesive")
		(11 "B.Adhes" user "B.Adhesive")
		(13 "F.Paste" user "Package Geometry/Pastemask Top")
		(15 "B.Paste" user "Package Geometry/Pastemask Bottom")
		(5 "F.SilkS" user "Ref Des/Silkscreen Top")
		(7 "B.SilkS" user "Ref Des/Silkscreen Bottom")
		(1 "F.Mask" user "Board Geometry/Soldermask Top")
		(3 "B.Mask" user "Board Geometry/Soldermask Bottom")
		(17 "Dwgs.User" user "User.Drawings")
		(19 "Cmts.User" user "User.Comments")
		(21 "Eco1.User" user "User.Eco1")
		(23 "Eco2.User" user "User.Eco2")
		(25 "Edge.Cuts" user "Board Geometry/Outline")
		(27 "Margin" user)
		(31 "F.CrtYd" user "Package Geometry/Place Bound Top")
		(29 "B.CrtYd" user "Package Geometry/Place Bound Bottom")
		(35 "F.Fab" user "Ref Des/Assembly Top")
		(33 "B.Fab" user "Ref Des/Assembly Bottom")
	)
	(footprint ""
		(layer "F.Cu")
		(at 85.1662 -101.9048 -90)
		(property "Reference" "U6"
			(at -0.3302 -2.88417 90)
			(unlocked yes)
			(layer "F.SilkS")
			(effects
				(font
					(size 0.7874 0.5842)
					(thickness 0.1524)
				)
			)
		)
		(property "Value" ""
			(at 0 0 270)
			(layer "F.Fab")
			(effects
				(font
					(size 1.27 1.27)
				)
			)
		)
		(property "Device Type" "TPS54824RNVR_VQFN18-G220-10657A"
			(at 0.33782 4.521454 270)
			(unlocked yes)
			(layer "F.Fab")
			(hide yes)
			(effects
				(font
					(size 0.7874 0.5842)
					(thickness 0.1524)
				)
			)
		)
		(property "User Part Number" "PARTNUM*"
			(at 0.33782 5.715254 270)
			(unlocked yes)
			(layer "Cmts.User")
			(hide yes)
			(effects
				(font
					(size 0.7874 0.5842)
					(thickness 0.1524)
				)
			)
		)
		(duplicate_pad_numbers_are_jumpers no)
		(fp_line
			(start -2.208784 2.200148)
			(end -2.208784 -2.208784)
			(stroke
				(width 0.1)
				(type default)
			)
			(layer "F.SilkS")
		)
		(fp_line
			(start 2.208784 2.200148)
			(end -2.208784 2.200148)
			(stroke
				(width 0.1)
				(type default)
			)
			(layer "F.SilkS")
		)
		(fp_line
			(start -2.208784 -2.208784)
			(end 2.208784 -2.208784)
			(stroke
				(width 0.1)
				(type default)
			)
			(layer "F.SilkS")
		)
		(fp_line
			(start 2.208784 -2.208784)
			(end 2.208784 2.200148)
			(stroke
				(width 0.1)
				(type default)
			)
			(layer "F.SilkS")
		)
		(fp_poly
			(pts
				(arc
					(start -3.084068 -1.50114)
					(mid -3.084068 -0.48514)
					(end -3.084068 -1.50114)
				)
			)
			(stroke
				(width 0)
				(type default)
			)
			(fill yes)
			(layer "F.SilkS")
		)
		(fp_rect
			(start 2.462784 2.454148)
			(end -2.462784 -2.462784)
			(stroke
				(width 0)
				(type default)
			)
			(fill no)
			(layer "F.CrtYd")
		)
		(fp_line
			(start -1.800098 1.800098)
			(end -1.800098 -1.800098)
			(stroke
				(width 0.1)
				(type default)
			)
			(layer "F.Fab")
		)
		(fp_line
			(start 1.800098 1.800098)
			(end -1.800098 1.800098)
			(stroke
				(width 0.1)
				(type default)
			)
			(layer "F.Fab")
		)
		(fp_line
			(start -1.800098 -1.800098)
			(end 1.800098 -1.800098)
			(stroke
				(width 0.1)
				(type default)
			)
			(layer "F.Fab")
		)
		(fp_line
			(start 1.800098 -1.800098)
			(end 1.800098 1.800098)
			(stroke
				(width 0.1)
				(type default)
			)
			(layer "F.Fab")
		)
		(fp_circle
			(center -2.468626 -1.148334)
			(end -2.468626 -1.656334)
			(stroke
				(width 0.1)
				(type default)
			)
			(fill no)
			(layer "F.Fab")
		)
		(fp_text user "8"
			(at 1.98755 2.9972 0)
			(unlocked yes)
			(layer "F.SilkS")
			(effects
				(font
					(size 0.635 0.4064)
					(thickness 0.1524)
				)
			)
		)
		(fp_text user "7"
			(at 0.71755 2.7432 0)
			(unlocked yes)
			(layer "F.SilkS")
			(effects
				(font
					(size 0.635 0.4064)
					(thickness 0.1524)
				)
			)
		)
		(fp_text user "5"
			(at -1.49225 2.6162 0)
			(unlocked yes)
			(layer "F.SilkS")
			(effects
				(font
					(size 0.635 0.4064)
					(thickness 0.1524)
				)
			)
		)
		(fp_text user "6"
			(at -0.34925 2.6162 0)
			(unlocked yes)
			(layer "F.SilkS")
			(effects
				(font
					(size 0.635 0.4064)
					(thickness 0.1524)
				)
			)
		)
		(fp_text user "12"
			(at 2.87655 -1.9558 0)
			(unlocked yes)
			(layer "F.SilkS")
			(effects
				(font
					(size 0.635 0.4064)
					(thickness 0.1524)
				)
			)
		)
		(fp_text user "18"
			(at -2.3622 -2.87655 90)
			(unlocked yes)
			(layer "F.SilkS")
			(effects
				(font
					(size 0.635 0.4064)
					(thickness 0.1524)
				)
			)
		)
		(fp_text user "13"
			(at 1.5748 -2.87655 90)
			(unlocked yes)
			(layer "F.SilkS")
			(effects
				(font
					(size 0.635 0.4064)
					(thickness 0.1524)
				)
			)
		)
		(fp_text user "6"
			(at -1.06553 2.3622 0)
			(unlocked yes)
			(layer "F.Fab")
			(effects
				(font
					(size 0.7874 0.5842)
					(thickness 0.1524)
				)
			)
		)
		(fp_text user "7"
			(at 1.09347 2.3622 0)
			(unlocked yes)
			(layer "F.Fab")
			(effects
				(font
					(size 0.7874 0.5842)
					(thickness 0.1524)
				)
			)
		)
		(fp_text user "5"
			(at -2.08153 2.1082 0)
			(unlocked yes)
			(layer "F.Fab")
			(effects
				(font
					(size 0.7874 0.5842)
					(thickness 0.1524)
				)
			)
		)
		(fp_text user "8"
			(at 2.36347 1.8542 0)
			(unlocked yes)
			(layer "F.Fab")
			(effects
				(font
					(size 0.7874 0.5842)
					(thickness 0.1524)
				)
			)
		)
		(fp_text user "12"
			(at 2.36347 -1.1938 0)
			(unlocked yes)
			(layer "F.Fab")
			(effects
				(font
					(size 0.7874 0.5842)
					(thickness 0.1524)
				)
			)
		)
		(fp_text user "18"
			(at -1.604264 -2.61747 0)
			(unlocked yes)
			(layer "F.Fab")
			(effects
				(font
					(size 0.7874 0.5842)
					(thickness 0.1524)
				)
			)
		)
		(fp_text user "13"
			(at 1.356868 -2.61747 0)
			(unlocked yes)
			(layer "F.Fab")
			(effects
				(font
					(size 0.7874 0.5842)
					(thickness 0.1524)
				)
			)
		)
		(pad "1" smd rect
			(at -1.649984 -0.94996 270)
			(size 0.6096 0.3048)
			(layers "F.Cu" "F.Mask" "F.Paste")
			(net "XP3R3V_BT")
		)
		(pad "2" smd rect
			(at -1.374902 -0.350012 270)
			(size 1.143 0.4064)
			(layers "F.Cu" "F.Mask" "F.Paste")
			(net "VIN_XP3R3")
		)
		(pad "3" smd rect
			(at -1.374902 0.299974 270)
			(size 1.143 0.3048)
			(layers "F.Cu" "F.Mask" "F.Paste")
			(net "SG")
		)
		(pad "4" smd rect
			(at -1.374902 0.849884 270)
			(size 1.143 0.3048)
			(layers "F.Cu" "F.Mask" "F.Paste")
			(net "SG")
		)
		(pad "5" smd rect
			(at -1.374902 1.400048 270)
			(size 1.143 0.3048)
			(layers "F.Cu" "F.Mask" "F.Paste")
			(net "SG")
		)
		(pad "6" smd rect
			(at -0.32512 0.599948 270)
			(size 0.2032 2.6924)
			(layers "F.Cu" "F.Mask" "F.Paste")
			(net "XP3R3V_SW")
		)
		(pad "7" smd rect
			(at 0.32512 0.599948 270)
			(size 0.2032 2.6924)
			(layers "F.Cu" "F.Mask" "F.Paste")
			(net "XP3R3V_SW")
		)
		(pad "8" smd rect
			(at 1.374902 1.400048 270)
			(size 1.143 0.3048)
			(layers "F.Cu" "F.Mask" "F.Paste")
			(net "SG")
		)
		(pad "9" smd rect
			(at 1.374902 0.849884 270)
			(size 1.143 0.3048)
			(layers "F.Cu" "F.Mask" "F.Paste")
			(net "SG")
		)
		(pad "10" smd rect
			(at 1.374902 0.299974 270)
			(size 1.143 0.3048)
			(layers "F.Cu" "F.Mask" "F.Paste")
			(net "SG")
		)
		(pad "11" smd rect
			(at 1.374902 -0.350012 270)
			(size 1.143 0.4064)
			(layers "F.Cu" "F.Mask" "F.Paste")
			(net "VIN_XP3R3")
		)
		(pad "12" smd rect
			(at 1.649984 -0.94996 270)
			(size 0.6096 0.3048)
			(layers "F.Cu" "F.Mask" "F.Paste")
			(net "XP3R3V_AGND")
		)
		(pad "13" smd rect
			(at 1.374902 -1.649984 270)
			(size 0.508 0.6096)
			(layers "F.Cu" "F.Mask" "F.Paste")
			(net "XP3R3V_RT")
		)
		(pad "14" smd rect
			(at 0.750062 -1.649984 270)
			(size 0.254 0.6096)
			(layers "F.Cu" "F.Mask" "F.Paste")
			(net "XP3R3V_FB_R_TO_AGND")
		)
		(pad "15" smd rect
			(at 0.249936 -1.649984 270)
			(size 0.254 0.6096)
			(layers "F.Cu" "F.Mask" "F.Paste")
			(net "XP3R3V_COMP")
		)
		(pad "16" smd rect
			(at -0.249936 -1.649984 270)
			(size 0.254 0.6096)
			(layers "F.Cu" "F.Mask" "F.Paste")
			(net "XP3R3V_SS")
		)
		(pad "17" smd rect
			(at -0.750062 -1.649984 270)
			(size 0.254 0.6096)
			(layers "F.Cu" "F.Mask" "F.Paste")
			(net "XP3R3V_EN")
		)
		(pad "18" smd rect
			(at -1.374902 -1.649984 270)
			(size 0.508 0.6096)
			(layers "F.Cu" "F.Mask" "F.Paste")
			(net "R_XP3R3V_PG")
		)
	)
)
